# S9S_MB_2U (Grand Teton) — schematic netlist excerpt (pin names and nets, part order shuffled) for the footprints in the layout excerpt that follows; sources: Cadence DE-HDL packaged netlist, KiCad conversion of 03242023_DA0F0TMBIJ0_F0T_Motherboard_J_brd_V01_OCP.brd

PC585  Q_CAPP  270UF 16V 20% OSCON  pkg THLF  page 285 : A = SW_P12V_PVCCIN_CPU1_FLT ; B = GND
R4259  Q_RES  33.2 1% CHIP  pkg 0402LF  page 214 : A = FM_THERMAL_ALERT_N ; B = FM_THERMAL_ALERT_R_N
PR1337  Q_RES  38.3K 0.1% CHIP  pkg 0402LF  page 281 : A = PVPP_HBM_CPU0_FB ; B = SH_PVPP_HBM_CPU0_P

(kicad_pcb
	(version 20260206)
	(generator "pcbnew")
	(generator_version "10.0")
	(general
		(thickness 1.6)
		(legacy_teardrops no)
	)
	(paper "A4")
	(title_block
		(title "03242023_DA0F0TMBIJ0_F0T_Motherboard_J_brd_V01_OCP.brd")
		(comment 1 "Grand Teton / footprints 54-56 of 6105")
	)
	(layers
		(0 "F.Cu" signal "TOP")
		(4 "In1.Cu" signal "GND")
		(6 "In2.Cu" signal "IN1")
		(8 "In3.Cu" signal "GND1")
		(10 "In4.Cu" signal "IN2")
		(12 "In5.Cu" signal "GND2")
		(14 "In6.Cu" signal "IN3")
		(16 "In7.Cu" signal "GND3")
		(18 "In8.Cu" signal "VCC")
		(20 "In9.Cu" signal "VCC1")
		(22 "In10.Cu" signal "GND4")
		(24 "In11.Cu" signal "IN4")
		(26 "In12.Cu" signal "GND5")
		(28 "In13.Cu" signal "IN5")
		(30 "In14.Cu" signal "GND6")
		(32 "In15.Cu" signal "IN6")
		(34 "In16.Cu" signal "GND7")
		(2 "B.Cu" signal "BOTTOM")
		(9 "F.Adhes" user "F.Adhesive")
		(11 "B.Adhes" user "B.Adhesive")
		(13 "F.Paste" user "Package Geometry/Pastemask Top")
		(15 "B.Paste" user "Package Geometry/Pastemask Bottom")
		(5 "F.SilkS" user "Ref Des/Silkscreen Top")
		(7 "B.SilkS" user "Ref Des/Silkscreen Bottom")
		(1 "F.Mask" user "Board Geometry/Soldermask Top")
		(3 "B.Mask" user "Board Geometry/Soldermask Bottom")
		(17 "Dwgs.User" user "User.Drawings")
		(19 "Cmts.User" user "User.Comments")
		(21 "Eco1.User" user "User.Eco1")
		(23 "Eco2.User" user "User.Eco2")
		(25 "Edge.Cuts" user "Board Geometry/Outline")
		(27 "Margin" user)
		(31 "F.CrtYd" user "Package Geometry/Place Bound Top")
		(29 "B.CrtYd" user "Package Geometry/Place Bound Bottom")
		(35 "F.Fab" user "Ref Des/Assembly Top")
		(33 "B.Fab" user "Ref Des/Assembly Bottom")
	)
	(footprint ""
		(layer "F.Cu")
		(at 176.58588 -133.695948 -90)
		(property "Reference" "R4259"
			(at 0 0 270)
			(layer "F.SilkS")
			(hide yes)
			(effects
				(font
					(size 1.27 1.27)
				)
			)
		)
		(property "Value" ""
			(at 0 0 270)
			(layer "F.Fab")
			(effects
				(font
					(size 1.27 1.27)
				)
			)
		)
		(duplicate_pad_numbers_are_jumpers no)
		(fp_line
			(start -0.7874 0.4064)
			(end -0.7874 -0.4064)
			(stroke
				(width 0.1524)
				(type default)
			)
			(layer "F.SilkS")
		)
		(fp_line
			(start 0.7874 0.4064)
			(end -0.7874 0.4064)
			(stroke
				(width 0.1524)
				(type default)
			)
			(layer "F.SilkS")
		)
		(fp_line
			(start -0.7874 -0.4064)
			(end 0.7874 -0.4064)
			(stroke
				(width 0.1524)
				(type default)
			)
			(layer "F.SilkS")
		)
		(fp_line
			(start 0.7874 -0.4064)
			(end 0.7874 0.4064)
			(stroke
				(width 0.1524)
				(type default)
			)
			(layer "F.SilkS")
		)
		(fp_line
			(start -0.67945 0.3048)
			(end -0.67945 -0.305054)
			(stroke
				(width 0.1)
				(type default)
			)
			(layer "F.Fab")
		)
		(fp_line
			(start -0.12065 0.3048)
			(end -0.67945 0.3048)
			(stroke
				(width 0.1)
				(type default)
			)
			(layer "F.Fab")
		)
		(fp_line
			(start 0.120396 0.3048)
			(end 0.120396 0.2794)
			(stroke
				(width 0.1)
				(type default)
			)
			(layer "F.Fab")
		)
		(fp_line
			(start 0.67945 0.3048)
			(end 0.120396 0.3048)
			(stroke
				(width 0.1)
				(type default)
			)
			(layer "F.Fab")
		)
		(fp_line
			(start -0.12065 0.2794)
			(end -0.12065 0.3048)
			(stroke
				(width 0.1)
				(type default)
			)
			(layer "F.Fab")
		)
		(fp_line
			(start 0.120396 0.2794)
			(end -0.12065 0.2794)
			(stroke
				(width 0.1)
				(type default)
			)
			(layer "F.Fab")
		)
		(fp_line
			(start -0.12065 -0.2794)
			(end 0.12065 -0.2794)
			(stroke
				(width 0.1)
				(type default)
			)
			(layer "F.Fab")
		)
		(fp_line
			(start 0.12065 -0.2794)
			(end 0.12065 -0.3048)
			(stroke
				(width 0.1)
				(type default)
			)
			(layer "F.Fab")
		)
		(fp_line
			(start 0.12065 -0.3048)
			(end 0.67945 -0.3048)
			(stroke
				(width 0.1)
				(type default)
			)
			(layer "F.Fab")
		)
		(fp_line
			(start 0.67945 -0.3048)
			(end 0.67945 0.3048)
			(stroke
				(width 0.1)
				(type default)
			)
			(layer "F.Fab")
		)
		(fp_line
			(start -0.67945 -0.305054)
			(end -0.12065 -0.305054)
			(stroke
				(width 0.1)
				(type default)
			)
			(layer "F.Fab")
		)
		(fp_line
			(start -0.12065 -0.305054)
			(end -0.12065 -0.2794)
			(stroke
				(width 0.1)
				(type default)
			)
			(layer "F.Fab")
		)
		(pad "1" smd circle
			(at -0.40005 0 270)
			(size 0 0)
			(layers "F.Cu" "F.Mask" "F.Paste")
			(net "FM_THERMAL_ALERT_N")
		)
		(pad "2" smd circle
			(at 0.40005 0 270)
			(size 0 0)
			(layers "F.Cu" "F.Mask" "F.Paste")
			(net "FM_THERMAL_ALERT_R_N")
		)
	)
	(footprint ""
		(layer "F.Cu")
		(at 368.005868 -357.11638 90)
		(property "Reference" "PR1337"
			(at 0 0 90)
			(layer "F.SilkS")
			(hide yes)
			(effects
				(font
					(size 1.27 1.27)
				)
			)
		)
		(property "Value" ""
			(at 0 0 90)
			(layer "F.Fab")
			(effects
				(font
					(size 1.27 1.27)
				)
			)
		)
		(duplicate_pad_numbers_are_jumpers no)
		(fp_line
			(start 0.7874 -0.4064)
			(end 0.7874 0.4064)
			(stroke
				(width 0.1524)
				(type default)
			)
			(layer "F.SilkS")
		)
		(fp_line
			(start -0.7874 -0.4064)
			(end 0.7874 -0.4064)
			(stroke
				(width 0.1524)
				(type default)
			)
			(layer "F.SilkS")
		)
		(fp_line
			(start 0.7874 0.4064)
			(end -0.7874 0.4064)
			(stroke
				(width 0.1524)
				(type default)
			)
			(layer "F.SilkS")
		)
		(fp_line
			(start -0.7874 0.4064)
			(end -0.7874 -0.4064)
			(stroke
				(width 0.1524)
				(type default)
			)
			(layer "F.SilkS")
		)
		(fp_line
			(start -0.12065 -0.305054)
			(end -0.12065 -0.2794)
			(stroke
				(width 0.1)
				(type default)
			)
			(layer "F.Fab")
		)
		(fp_line
			(start -0.67945 -0.305054)
			(end -0.12065 -0.305054)
			(stroke
				(width 0.1)
				(type default)
			)
			(layer "F.Fab")
		)
		(fp_line
			(start 0.67945 -0.3048)
			(end 0.67945 0.3048)
			(stroke
				(width 0.1)
				(type default)
			)
			(layer "F.Fab")
		)
		(fp_line
			(start 0.12065 -0.3048)
			(end 0.67945 -0.3048)
			(stroke
				(width 0.1)
				(type default)
			)
			(layer "F.Fab")
		)
		(fp_line
			(start 0.12065 -0.2794)
			(end 0.12065 -0.3048)
			(stroke
				(width 0.1)
				(type default)
			)
			(layer "F.Fab")
		)
		(fp_line
			(start -0.12065 -0.2794)
			(end 0.12065 -0.2794)
			(stroke
				(width 0.1)
				(type default)
			)
			(layer "F.Fab")
		)
		(fp_line
			(start 0.120396 0.2794)
			(end -0.12065 0.2794)
			(stroke
				(width 0.1)
				(type default)
			)
			(layer "F.Fab")
		)
		(fp_line
			(start -0.12065 0.2794)
			(end -0.12065 0.3048)
			(stroke
				(width 0.1)
				(type default)
			)
			(layer "F.Fab")
		)
		(fp_line
			(start 0.67945 0.3048)
			(end 0.120396 0.3048)
			(stroke
				(width 0.1)
				(type default)
			)
			(layer "F.Fab")
		)
		(fp_line
			(start 0.120396 0.3048)
			(end 0.120396 0.2794)
			(stroke
				(width 0.1)
				(type default)
			)
			(layer "F.Fab")
		)
		(fp_line
			(start -0.12065 0.3048)
			(end -0.67945 0.3048)
			(stroke
				(width 0.1)
				(type default)
			)
			(layer "F.Fab")
		)
		(fp_line
			(start -0.67945 0.3048)
			(end -0.67945 -0.305054)
			(stroke
				(width 0.1)
				(type default)
			)
			(layer "F.Fab")
		)
		(pad "1" smd circle
			(at -0.40005 0 90)
			(size 0 0)
			(layers "F.Cu" "F.Mask" "F.Paste")
			(net "PVPP_HBM_CPU0_FB")
		)
		(pad "2" smd circle
			(at 0.40005 0 90)
			(size 0 0)
			(layers "F.Cu" "F.Mask" "F.Paste")
			(net "SH_PVPP_HBM_CPU0_P")
		)
	)
	(footprint ""
		(layer "F.Cu")
		(at 120.0658 -343.906348 90)
		(property "Reference" "PC585"
			(at 0 0 90)
			(layer "F.SilkS")
			(hide yes)
			(effects
				(font
					(size 1.27 1.27)
				)
			)
		)
		(property "Value" ""
			(at 0 0 90)
			(layer "F.Fab")
			(effects
				(font
					(size 1.27 1.27)
				)
			)
		)
		(duplicate_pad_numbers_are_jumpers no)
		(fp_line
			(start -3.400044 1.249934)
			(end 3.400044 1.249934)
			(stroke
				(width 0.1524)
				(type default)
			)
			(layer "F.SilkS")
		)
		(fp_circle
			(center 0 1.249934)
			(end 0 4.649978)
			(stroke
				(width 0.1524)
				(type default)
			)
			(fill no)
			(layer "F.SilkS")
		)
		(fp_poly
			(pts
				(arc
					(start -3.400044 1.249934)
					(mid 0 4.649978)
					(end 3.400044 1.249934)
				)
			)
			(stroke
				(width 0)
				(type default)
			)
			(fill yes)
			(layer "F.SilkS")
		)
		(fp_circle
			(center 0 1.249934)
			(end 0 4.649978)
			(stroke
				(width 0.1)
				(type default)
			)
			(fill no)
			(layer "F.Fab")
		)
		(pad "1" thru_hole rect
			(at 0 0 90)
			(size 1.524 1.524)
			(drill 1.016)
			(layers "*.Cu" "*.Mask")
			(remove_unused_layers no)
			(net "SW_P12V_PVCCIN_CPU1_FLT")
			(clearance 0)
			(padstack
				(mode front_inner_back)
				(layer "Inner"
					(shape circle)
					(size 1.524 1.524)
					(clearance 0)
				)
				(layer "B.Cu"
					(shape rect)
					(size 1.524 1.524)
					(clearance 0)
				)
			)
		)
		(pad "2" thru_hole circle
			(at 0 2.500122 90)
			(size 1.524 1.524)
			(drill 1.016)
			(layers "*.Cu" "*.Mask")
			(remove_unused_layers no)
			(net "GND")
			(clearance 0)
		)
	)
)
